(kicad_pcb
	(version 20241229)
	(generator "pcbnew")
	(generator_version "9.0")
	(general
		(thickness 1.6642)
		(legacy_teardrops no)
	)
	(paper "A3")
	(title_block
		(title "PolarFire SoM")
		(date "2025-07-22")
		(rev "1.1.4")
		(company "Antmicro Ltd")
		(comment 1 "www.antmicro.com")
		(comment 9 "footprints 343-346 of 470")
	)
	(layers
		(0 "F.Cu" mixed)
		(4 "In1.Cu" power)
		(6 "In2.Cu" signal)
		(8 "In3.Cu" power)
		(10 "In4.Cu" signal)
		(12 "In5.Cu" power)
		(14 "In6.Cu" power)
		(16 "In7.Cu" signal)
		(18 "In8.Cu" power)
		(20 "In9.Cu" signal)
		(22 "In10.Cu" power)
		(24 "In11.Cu" signal)
		(26 "In12.Cu" signal)
		(2 "B.Cu" mixed)
		(9 "F.Adhes" user "F.Adhesive")
		(11 "B.Adhes" user "B.Adhesive")
		(13 "F.Paste" user)
		(15 "B.Paste" user)
		(5 "F.SilkS" user "F.Silkscreen")
		(7 "B.SilkS" user "B.Silkscreen")
		(1 "F.Mask" user)
		(3 "B.Mask" user)
		(17 "Dwgs.User" user "User.Drawings")
		(19 "Cmts.User" user "User.Comments")
		(21 "Eco1.User" user "User.Eco1")
		(23 "Eco2.User" user "User.Eco2")
		(25 "Edge.Cuts" user)
		(27 "Margin" user)
		(31 "F.CrtYd" user "F.Courtyard")
		(29 "B.CrtYd" user "B.Courtyard")
		(35 "F.Fab" user)
		(33 "B.Fab" user)
	)
	(footprint "antmicro-footprints:XSON-8_1x1.95mm_P0.5mm"
		(layer "B.Cu")
		(at 222.77 141.61)
		(property "Reference" "U25"
			(at 1.81 -0.63 0)
			(layer "B.SilkS")
			(effects
				(font
					(size 0.7 0.7)
					(thickness 0.15)
				)
				(justify right bottom mirror)
			)
		)
		(property "Value" "NTS0102_XSON"
			(at 0 -2.2 0)
			(layer "B.Fab")
			(hide yes)
			(effects
				(font
					(size 0.7 0.7)
					(thickness 0.15)
				)
				(justify right bottom mirror)
			)
		)
		(property "Datasheet" "http://www.farnell.com/datasheets/1760723.pdf"
			(at 0 0 0)
			(layer "F.Fab")
			(hide yes)
			(effects
				(font
					(size 1.27 1.27)
					(thickness 0.15)
				)
			)
		)
		(property "Description" "Transceiver, 1.65 V to 3.6 V, XSON-8"
			(at 0 0 0)
			(layer "F.Fab")
			(hide yes)
			(effects
				(font
					(size 1.27 1.27)
					(thickness 0.15)
				)
			)
		)
		(property "Author" "Antmicro"
			(at 0 0 0)
			(layer "B.Fab")
			(hide yes)
			(effects
				(font
					(size 1 1)
					(thickness 0.15)
				)
				(justify mirror)
			)
		)
		(property "License" "Apache-2.0"
			(at 0 0 0)
			(layer "B.Fab")
			(hide yes)
			(effects
				(font
					(size 1 1)
					(thickness 0.15)
				)
				(justify mirror)
			)
		)
		(property "MPN" "NTS0102GT"
			(at 0 0 0)
			(layer "B.Fab")
			(hide yes)
			(effects
				(font
					(size 1 1)
					(thickness 0.15)
				)
				(justify mirror)
			)
		)
		(property "Manufacturer" "NXP"
			(at 0 0 0)
			(layer "B.Fab")
			(hide yes)
			(effects
				(font
					(size 1 1)
					(thickness 0.15)
				)
				(justify mirror)
			)
		)
		(sheetname "/FPGA GPIO/")
		(sheetfile "fpga-gpio.kicad_sch")
		(attr smd)
		(fp_line
			(start -0.5 1.1)
			(end 0.5 1.1)
			(stroke
				(width 0.15)
				(type solid)
			)
			(layer "B.SilkS")
		)
		(fp_line
			(start 0.5 -1.1)
			(end -0.5 -1.1)
			(stroke
				(width 0.15)
				(type solid)
			)
			(layer "B.SilkS")
		)
		(fp_circle
			(center -0.75 1.1)
			(end -0.701 1.1)
			(stroke
				(width 0.15)
				(type solid)
			)
			(fill no)
			(layer "B.SilkS")
		)
		(fp_rect
			(start -0.8 1.2)
			(end 0.8 -1.2)
			(stroke
				(width 0.05)
				(type solid)
			)
			(fill no)
			(layer "B.CrtYd")
		)
		(fp_line
			(start -0.5305 -1)
			(end -0.5305 1.001)
			(stroke
				(width 0.15)
				(type solid)
			)
			(layer "B.Fab")
		)
		(fp_line
			(start -0.5305 1.001)
			(end 0.5305 1.001)
			(stroke
				(width 0.15)
				(type solid)
			)
			(layer "B.Fab")
		)
		(fp_line
			(start 0.5305 -1)
			(end -0.5305 -1)
			(stroke
				(width 0.15)
				(type solid)
			)
			(layer "B.Fab")
		)
		(fp_line
			(start 0.5305 1.001)
			(end 0.5305 -1)
			(stroke
				(width 0.15)
				(type solid)
			)
			(layer "B.Fab")
		)
		(fp_text user "${REFERENCE}"
			(at -0.527 -5.905 180)
			(layer "B.Fab")
			(effects
				(font
					(size 0.7 0.7)
					(thickness 0.15)
				)
				(justify left bottom mirror)
			)
		)
		(fp_text user "License: Apache-2.0"
			(at -0.527 -8.306 180)
			(layer "B.Fab")
			(effects
				(font
					(size 0.7 0.7)
					(thickness 0.15)
				)
				(justify left bottom mirror)
			)
		)
		(fp_text user "Author: Antmicro"
			(at -0.527 -7.105 180)
			(layer "B.Fab")
			(effects
				(font
					(size 0.7 0.7)
					(thickness 0.15)
				)
				(justify left bottom mirror)
			)
		)
		(pad "1" smd roundrect
			(at -0.45 0.75 180)
			(size 0.6 0.3)
			(layers "B.Cu" "B.Mask" "B.Paste")
			(roundrect_rratio 0.25)
			(net 226 "/FPGA GPIO/WiFi.DAT1")
			(pinfunction "B_{2}")
			(pintype "bidirectional")
		)
		(pad "2" smd roundrect
			(at -0.45 0.25 180)
			(size 0.6 0.25)
			(layers "B.Cu" "B.Mask" "B.Paste")
			(roundrect_rratio 0.25)
			(net 417 "GND")
			(pinfunction "GND")
			(pintype "power_in")
		)
		(pad "3" smd roundrect
			(at -0.45 -0.25 180)
			(size 0.6 0.25)
			(layers "B.Cu" "B.Mask" "B.Paste")
			(roundrect_rratio 0.25)
			(net 649 "VDD")
			(pinfunction "VCC_{A}")
			(pintype "power_in")
		)
		(pad "4" smd roundrect
			(at -0.45 -0.75 180)
			(size 0.6 0.3)
			(layers "B.Cu" "B.Mask" "B.Paste")
			(roundrect_rratio 0.25)
			(net 355 "/FPGA GPIO/WiFi_DATA_1")
			(pinfunction "A_{2}")
			(pintype "bidirectional")
		)
		(pad "5" smd roundrect
			(at 0.45 -0.75 180)
			(size 0.6 0.3)
			(layers "B.Cu" "B.Mask" "B.Paste")
			(roundrect_rratio 0.25)
			(net 358 "/FPGA GPIO/WiFi_CMD")
			(pinfunction "A_{1}")
			(pintype "bidirectional")
		)
		(pad "6" smd roundrect
			(at 0.45 -0.25 180)
			(size 0.6 0.25)
			(layers "B.Cu" "B.Mask" "B.Paste")
			(roundrect_rratio 0.25)
			(net 649 "VDD")
			(pinfunction "OE")
			(pintype "input")
		)
		(pad "7" smd roundrect
			(at 0.45 0.25 180)
			(size 0.6 0.25)
			(layers "B.Cu" "B.Mask" "B.Paste")
			(roundrect_rratio 0.25)
			(net 50 "+3V3")
			(pinfunction "VCC_{B}")
			(pintype "power_in")
		)
		(pad "8" smd roundrect
			(at 0.45 0.75 180)
			(size 0.6 0.3)
			(layers "B.Cu" "B.Mask" "B.Paste")
			(roundrect_rratio 0.25)
			(net 231 "/FPGA GPIO/WiFi.CMD")
			(pinfunction "B_{1}")
			(pintype "bidirectional")
		)
	)
	(footprint "antmicro-footprints:C_0402_1005Metric"
		(layer "B.Cu")
		(at 183.3 152.025 90)
		(descr "Capacitor SMD 0402")
		(tags "capacitor SMD 0402")
		(property "Reference" "C111"
			(at 0.675 0.35 90)
			(layer "B.SilkS")
			(effects
				(font
					(size 0.7 0.7)
					(thickness 0.15)
				)
				(justify right bottom mirror)
			)
		)
		(property "Value" "C_22p_0402"
			(at -1.022927 -2.155213 90)
			(layer "B.Fab")
			(hide yes)
			(effects
				(font
					(size 0.7 0.7)
					(thickness 0.15)
				)
				(justify right bottom mirror)
			)
		)
		(property "Datasheet" "https://www.yageo.com/en/Chart/Download/pdf/CC0402JRNPO9BN220"
			(at 0 0 90)
			(layer "F.Fab")
			(hide yes)
			(effects
				(font
					(size 1.27 1.27)
					(thickness 0.15)
				)
			)
		)
		(property "Description" "SMD Multilayer Ceramic Capacitor, 22 pF, 50 V, 0402 [1005 Metric], ± 5%, C0G / NP0, CC Series"
			(at 0 0 90)
			(layer "F.Fab")
			(hide yes)
			(effects
				(font
					(size 1.27 1.27)
					(thickness 0.15)
				)
			)
		)
		(property "Author" "Antmicro"
			(at 335.325 -31.275 0)
			(layer "B.Fab")
			(hide yes)
			(effects
				(font
					(size 1 1)
					(thickness 0.15)
				)
				(justify mirror)
			)
		)
		(property "Dielectric" ""
			(at 335.325 -31.275 0)
			(layer "B.Fab")
			(hide yes)
			(effects
				(font
					(size 1 1)
					(thickness 0.15)
				)
				(justify mirror)
			)
		)
		(property "License" "Apache-2.0"
			(at 335.325 -31.275 0)
			(layer "B.Fab")
			(hide yes)
			(effects
				(font
					(size 1 1)
					(thickness 0.15)
				)
				(justify mirror)
			)
		)
		(property "MPN" "CC0402JRNPO9BN220"
			(at 335.325 -31.275 0)
			(layer "B.Fab")
			(hide yes)
			(effects
				(font
					(size 1 1)
					(thickness 0.15)
				)
				(justify mirror)
			)
		)
		(property "Manufacturer" "YAGEO"
			(at 335.325 -31.275 0)
			(layer "B.Fab")
			(hide yes)
			(effects
				(font
					(size 1 1)
					(thickness 0.15)
				)
				(justify mirror)
			)
		)
		(property "Public" ""
			(at 335.325 -31.275 0)
			(layer "B.Fab")
			(hide yes)
			(effects
				(font
					(size 1 1)
					(thickness 0.15)
				)
				(justify mirror)
			)
		)
		(property "Val" "22p"
			(at 335.325 -31.275 0)
			(layer "B.Fab")
			(hide yes)
			(effects
				(font
					(size 1 1)
					(thickness 0.15)
				)
				(justify mirror)
			)
		)
		(property "Voltage" ""
			(at 335.325 -31.275 0)
			(layer "B.Fab")
			(hide yes)
			(effects
				(font
					(size 1 1)
					(thickness 0.15)
				)
				(justify mirror)
			)
		)
		(sheetname "/Supply/")
		(sheetfile "supply.kicad_sch")
		(attr smd)
		(fp_rect
			(start -0.925 0.47)
			(end 0.925 -0.47)
			(stroke
				(width 0.05)
				(type default)
			)
			(fill no)
			(layer "B.CrtYd")
		)
		(fp_line
			(start 0.504 -0.248)
			(end -0.494 -0.248)
			(stroke
				(width 0.15)
				(type solid)
			)
			(layer "B.Fab")
		)
		(fp_line
			(start -0.494 -0.248)
			(end -0.494 0.25)
			(stroke
				(width 0.15)
				(type solid)
			)
			(layer "B.Fab")
		)
		(fp_line
			(start 0.504 0.25)
			(end 0.504 -0.248)
			(stroke
				(width 0.15)
				(type solid)
			)
			(layer "B.Fab")
		)
		(fp_line
			(start -0.494 0.25)
			(end 0.504 0.25)
			(stroke
				(width 0.15)
				(type solid)
			)
			(layer "B.Fab")
		)
		(fp_text user "License: Apache-2.0"
			(at -0.939 -5.799 270)
			(layer "B.Fab")
			(effects
				(font
					(size 0.7 0.7)
					(thickness 0.15)
				)
				(justify left bottom mirror)
			)
		)
		(fp_text user "Author: Antmicro"
			(at -0.939 -3.399 270)
			(layer "B.Fab")
			(effects
				(font
					(size 0.7 0.7)
					(thickness 0.15)
				)
				(justify left bottom mirror)
			)
		)
		(fp_text user "${REFERENCE}"
			(at -0.939 -4.599 270)
			(layer "B.Fab")
			(effects
				(font
					(size 0.7 0.7)
					(thickness 0.15)
				)
				(justify left bottom mirror)
			)
		)
		(pad "1" smd roundrect
			(at -0.48 0 90)
			(size 0.59 0.64)
			(layers "B.Cu" "B.Mask" "B.Paste")
			(roundrect_rratio 0.25)
			(net 14 "Net-(C111-Pad1)")
			(pintype "passive")
		)
		(pad "2" smd roundrect
			(at 0.48 0 90)
			(size 0.59 0.64)
			(layers "B.Cu" "B.Mask" "B.Paste")
			(roundrect_rratio 0.25)
			(net 522 "/Supply/1V05_REG")
			(pintype "passive")
		)
	)
	(footprint "antmicro-footprints:C_0402_1005Metric"
		(layer "B.Cu")
		(at 213.861 120.754 180)
		(descr "Capacitor SMD 0402")
		(tags "capacitor SMD 0402")
		(property "Reference" "C255"
			(at -15.389 -13.246 0)
			(layer "B.SilkS")
			(effects
				(font
					(size 0.7 0.7)
					(thickness 0.15)
				)
				(justify left bottom mirror)
			)
		)
		(property "Value" "C_10n_0402"
			(at -1.022927 -2.155213 0)
			(layer "B.Fab")
			(hide yes)
			(effects
				(font
					(size 0.7 0.7)
					(thickness 0.15)
				)
				(justify left bottom mirror)
			)
		)
		(property "Datasheet" "https://www.murata.com/products/productdetail?partno=GRM155R71H103KA88%23"
			(at 0 0 180)
			(layer "F.Fab")
			(hide yes)
			(effects
				(font
					(size 1.27 1.27)
					(thickness 0.15)
				)
			)
		)
		(property "Description" "SMD Multilayer Ceramic Capacitor, 10000 pF, 50 V, 0402 [1005 Metric], ± 10%, X7R, GRM Series"
			(at 0 0 180)
			(layer "F.Fab")
			(hide yes)
			(effects
				(font
					(size 1.27 1.27)
					(thickness 0.15)
				)
			)
		)
		(property "Author" "Antmicro"
			(at 427.722 241.508 0)
			(layer "B.Fab")
			(hide yes)
			(effects
				(font
					(size 1 1)
					(thickness 0.15)
				)
				(justify mirror)
			)
		)
		(property "Dielectric" "X7R"
			(at 427.722 241.508 0)
			(layer "B.Fab")
			(hide yes)
			(effects
				(font
					(size 1 1)
					(thickness 0.15)
				)
				(justify mirror)
			)
		)
		(property "License" "Apache-2.0"
			(at 427.722 241.508 0)
			(layer "B.Fab")
			(hide yes)
			(effects
				(font
					(size 1 1)
					(thickness 0.15)
				)
				(justify mirror)
			)
		)
		(property "MPN" "GRM155R71H103KA88D"
			(at 427.722 241.508 0)
			(layer "B.Fab")
			(hide yes)
			(effects
				(font
					(size 1 1)
					(thickness 0.15)
				)
				(justify mirror)
			)
		)
		(property "Manufacturer" "Murata"
			(at 427.722 241.508 0)
			(layer "B.Fab")
			(hide yes)
			(effects
				(font
					(size 1 1)
					(thickness 0.15)
				)
				(justify mirror)
			)
		)
		(property "Public" ""
			(at 427.722 241.508 0)
			(layer "B.Fab")
			(hide yes)
			(effects
				(font
					(size 1 1)
					(thickness 0.15)
				)
				(justify mirror)
			)
		)
		(property "Val" "10n"
			(at 427.722 241.508 0)
			(layer "B.Fab")
			(hide yes)
			(effects
				(font
					(size 1 1)
					(thickness 0.15)
				)
				(justify mirror)
			)
		)
		(property "Voltage" "50V"
			(at 427.722 241.508 0)
			(layer "B.Fab")
			(hide yes)
			(effects
				(font
					(size 1 1)
					(thickness 0.15)
				)
				(justify mirror)
			)
		)
		(sheetname "/Ethernet/")
		(sheetfile "ethernet.kicad_sch")
		(attr smd)
		(fp_rect
			(start -0.925 0.47)
			(end 0.925 -0.47)
			(stroke
				(width 0.05)
				(type default)
			)
			(fill no)
			(layer "B.CrtYd")
		)
		(fp_line
			(start 0.504 0.25)
			(end 0.504 -0.248)
			(stroke
				(width 0.15)
				(type solid)
			)
			(layer "B.Fab")
		)
		(fp_line
			(start 0.504 -0.248)
			(end -0.494 -0.248)
			(stroke
				(width 0.15)
				(type solid)
			)
			(layer "B.Fab")
		)
		(fp_line
			(start -0.494 0.25)
			(end 0.504 0.25)
			(stroke
				(width 0.15)
				(type solid)
			)
			(layer "B.Fab")
		)
		(fp_line
			(start -0.494 -0.248)
			(end -0.494 0.25)
			(stroke
				(width 0.15)
				(type solid)
			)
			(layer "B.Fab")
		)
		(fp_text user "Author: Antmicro"
			(at -0.939 -3.399 0)
			(layer "B.Fab")
			(effects
				(font
					(size 0.7 0.7)
					(thickness 0.15)
				)
				(justify left bottom mirror)
			)
		)
		(fp_text user "License: Apache-2.0"
			(at -0.939 -5.799 0)
			(layer "B.Fab")
			(effects
				(font
					(size 0.7 0.7)
					(thickness 0.15)
				)
				(justify left bottom mirror)
			)
		)
		(fp_text user "${REFERENCE}"
			(at -0.939 -4.599 0)
			(layer "B.Fab")
			(effects
				(font
					(size 0.7 0.7)
					(thickness 0.15)
				)
				(justify left bottom mirror)
			)
		)
		(pad "1" smd roundrect
			(at -0.48 0 180)
			(size 0.59 0.64)
			(layers "B.Cu" "B.Mask" "B.Paste")
			(roundrect_rratio 0.25)
			(net 417 "GND")
			(pintype "passive")
		)
		(pad "2" smd roundrect
			(at 0.48 0 180)
			(size 0.59 0.64)
			(layers "B.Cu" "B.Mask" "B.Paste")
			(roundrect_rratio 0.25)
			(net 47 "+1V05")
			(pintype "passive")
		)
	)
	(footprint "antmicro-footprints:C_0402_1005Metric"
		(layer "B.Cu")
		(at 198 130.83 90)
		(descr "Capacitor SMD 0402")
		(tags "capacitor SMD 0402")
		(property "Reference" "C232"
			(at 5.18 -9.525 90)
			(layer "B.SilkS")
			(effects
				(font
					(size 0.7 0.7)
					(thickness 0.15)
				)
				(justify right bottom mirror)
			)
		)
		(property "Value" "C_100n_0402"
			(at -1.022927 -2.155213 90)
			(layer "B.Fab")
			(hide yes)
			(effects
				(font
					(size 0.7 0.7)
					(thickness 0.15)
				)
				(justify right bottom mirror)
			)
		)
		(property "Datasheet" "https://www.murata.com/products/productdetail?partno=GRM155R61H104KE14%23"
			(at 0 0 90)
			(layer "F.Fab")
			(hide yes)
			(effects
				(font
					(size 1.27 1.27)
					(thickness 0.15)
				)
			)
		)
		(property "Description" "SMD Multilayer Ceramic Capacitor, 0.1 µF, 50 V, 0402 [1005 Metric], ± 10%, X5R, GRM Series"
			(at 0 0 90)
			(layer "F.Fab")
			(hide yes)
			(effects
				(font
					(size 1.27 1.27)
					(thickness 0.15)
				)
			)
		)
		(property "Author" "Antmicro"
			(at 328.83 -67.17 0)
			(layer "B.Fab")
			(hide yes)
			(effects
				(font
					(size 1 1)
					(thickness 0.15)
				)
				(justify mirror)
			)
		)
		(property "Dielectric" "X5R"
			(at 328.83 -67.17 0)
			(layer "B.Fab")
			(hide yes)
			(effects
				(font
					(size 1 1)
					(thickness 0.15)
				)
				(justify mirror)
			)
		)
		(property "License" "Apache-2.0"
			(at 328.83 -67.17 0)
			(layer "B.Fab")
			(hide yes)
			(effects
				(font
					(size 1 1)
					(thickness 0.15)
				)
				(justify mirror)
			)
		)
		(property "MPN" "GRM155R61H104KE14D"
			(at 328.83 -67.17 0)
			(layer "B.Fab")
			(hide yes)
			(effects
				(font
					(size 1 1)
					(thickness 0.15)
				)
				(justify mirror)
			)
		)
		(property "Manufacturer" "Murata"
			(at 328.83 -67.17 0)
			(layer "B.Fab")
			(hide yes)
			(effects
				(font
					(size 1 1)
					(thickness 0.15)
				)
				(justify mirror)
			)
		)
		(property "Public" ""
			(at 328.83 -67.17 0)
			(layer "B.Fab")
			(hide yes)
			(effects
				(font
					(size 1 1)
					(thickness 0.15)
				)
				(justify mirror)
			)
		)
		(property "Val" "100n"
			(at 328.83 -67.17 0)
			(layer "B.Fab")
			(hide yes)
			(effects
				(font
					(size 1 1)
					(thickness 0.15)
				)
				(justify mirror)
			)
		)
		(property "Voltage" "50V"
			(at 328.83 -67.17 0)
			(layer "B.Fab")
			(hide yes)
			(effects
				(font
					(size 1 1)
					(thickness 0.15)
				)
				(justify mirror)
			)
		)
		(sheetname "/FPGA Supply/")
		(sheetfile "fpga-supply.kicad_sch")
		(attr smd)
		(fp_rect
			(start -0.925 0.47)
			(end 0.925 -0.47)
			(stroke
				(width 0.05)
				(type default)
			)
			(fill no)
			(layer "B.CrtYd")
		)
		(fp_line
			(start 0.504 -0.248)
			(end -0.494 -0.248)
			(stroke
				(width 0.15)
				(type solid)
			)
			(layer "B.Fab")
		)
		(fp_line
			(start -0.494 -0.248)
			(end -0.494 0.25)
			(stroke
				(width 0.15)
				(type solid)
			)
			(layer "B.Fab")
		)
		(fp_line
			(start 0.504 0.25)
			(end 0.504 -0.248)
			(stroke
				(width 0.15)
				(type solid)
			)
			(layer "B.Fab")
		)
		(fp_line
			(start -0.494 0.25)
			(end 0.504 0.25)
			(stroke
				(width 0.15)
				(type solid)
			)
			(layer "B.Fab")
		)
		(fp_text user "License: Apache-2.0"
			(at -0.939 -5.799 270)
			(layer "B.Fab")
			(effects
				(font
					(size 0.7 0.7)
					(thickness 0.15)
				)
				(justify left bottom mirror)
			)
		)
		(fp_text user "Author: Antmicro"
			(at -0.939 -3.399 270)
			(layer "B.Fab")
			(effects
				(font
					(size 0.7 0.7)
					(thickness 0.15)
				)
				(justify left bottom mirror)
			)
		)
		(fp_text user "${REFERENCE}"
			(at -0.939 -4.599 270)
			(layer "B.Fab")
			(effects
				(font
					(size 0.7 0.7)
					(thickness 0.15)
				)
				(justify left bottom mirror)
			)
		)
		(pad "1" smd roundrect
			(at -0.48 0 90)
			(size 0.59 0.64)
			(layers "B.Cu" "B.Mask" "B.Paste")
			(roundrect_rratio 0.25)
			(net 417 "GND")
			(pintype "passive")
		)
		(pad "2" smd roundrect
			(at 0.48 0 90)
			(size 0.59 0.64)
			(layers "B.Cu" "B.Mask" "B.Paste")
			(roundrect_rratio 0.25)
			(net 49 "VDDAUX")
			(pintype "passive")
		)
	)
)
